# BASEBOARD_FAB2 (Tioga Pass) — schematic netlist excerpt (pin names and nets, part order shuffled) for the footprints in the layout excerpt that follows; sources: Cadence DE-HDL packaged netlist, KiCad conversion of Wiwynn_Tioga_Pass_MB.brd

R1D12  RES  10.0K 1% CHIP  pkg 0402  page 200 : A = A_HSC_LOW ; B = AGND_HSC
T1P25  TPAD-SE-2P-GP  pkg DISCRET-GA1  page 256 : \1\ = L1_40OHM_6INCH ; GND1 = GND
C1C25  CAP_A  0.1UF 16V 10% X7R  pkg 0402V  page 209 : A = VR_FET_SW_P12V_STBY_PVCCIN_CPU1 ; B = GND

(kicad_pcb
	(version 20260206)
	(generator "pcbnew")
	(generator_version "10.0")
	(general
		(thickness 1.6)
		(legacy_teardrops no)
	)
	(paper "A4")
	(title_block
		(title "Wiwynn_Tioga_Pass_MB.brd")
		(comment 1 "Tioga Pass / footprints 1674-1676 of 4770")
	)
	(layers
		(0 "F.Cu" signal "TOP")
		(4 "In1.Cu" signal "L2GND")
		(6 "In2.Cu" signal "L3")
		(8 "In3.Cu" signal "L4GND")
		(10 "In4.Cu" signal "L5")
		(12 "In5.Cu" signal "L6GND")
		(14 "In6.Cu" signal "L7VCC")
		(16 "In7.Cu" signal "L8VCC")
		(18 "In8.Cu" signal "L9GND")
		(20 "In9.Cu" signal "L10")
		(22 "In10.Cu" signal "L11GND")
		(24 "In11.Cu" signal "L12")
		(26 "In12.Cu" signal "L13GND")
		(2 "B.Cu" signal "BOTTOM")
		(9 "F.Adhes" user "F.Adhesive")
		(11 "B.Adhes" user "B.Adhesive")
		(13 "F.Paste" user "Package Geometry/Pastemask Top")
		(15 "B.Paste" user "Package Geometry/Pastemask Bottom")
		(5 "F.SilkS" user "Ref Des/Silkscreen Top")
		(7 "B.SilkS" user "Ref Des/Silkscreen Bottom")
		(1 "F.Mask" user "Board Geometry/Soldermask Top")
		(3 "B.Mask" user "Board Geometry/Soldermask Bottom")
		(17 "Dwgs.User" user "User.Drawings")
		(19 "Cmts.User" user "User.Comments")
		(21 "Eco1.User" user "User.Eco1")
		(23 "Eco2.User" user "User.Eco2")
		(25 "Edge.Cuts" user "Board Geometry/Outline")
		(27 "Margin" user)
		(31 "F.CrtYd" user "Package Geometry/Place Bound Top")
		(29 "B.CrtYd" user "Package Geometry/Place Bound Bottom")
		(35 "F.Fab" user "Ref Des/Assembly Top")
		(33 "B.Fab" user "Ref Des/Assembly Bottom")
	)
	(footprint ""
		(layer "F.Cu")
		(at 23.46198 -84.14258)
		(property "Reference" "R1D12"
			(at 0 0 0)
			(layer "F.SilkS")
			(hide yes)
			(effects
				(font
					(size 1.27 1.27)
				)
			)
		)
		(property "Value" ""
			(at 0 0 0)
			(layer "F.Fab")
			(effects
				(font
					(size 1.27 1.27)
				)
			)
		)
		(duplicate_pad_numbers_are_jumpers no)
		(fp_poly
			(pts
				(xy -0.2794 -0.1016) (xy 0.2794 -0.1016) (xy 0.2794 0.9906) (xy -0.2794 0.9906)
			)
			(stroke
				(width 0)
				(type default)
			)
			(fill no)
			(layer "F.CrtYd")
		)
		(fp_line
			(start -0.2794 -0.1016)
			(end -0.2794 0.9906)
			(stroke
				(width 0.1)
				(type default)
			)
			(layer "F.Fab")
		)
		(fp_line
			(start -0.2794 0.9906)
			(end 0.2794 0.9906)
			(stroke
				(width 0.1)
				(type default)
			)
			(layer "F.Fab")
		)
		(fp_line
			(start 0.2794 -0.1016)
			(end -0.2794 -0.1016)
			(stroke
				(width 0.1)
				(type default)
			)
			(layer "F.Fab")
		)
		(fp_line
			(start 0.2794 0.9906)
			(end 0.2794 -0.1016)
			(stroke
				(width 0.1)
				(type default)
			)
			(layer "F.Fab")
		)
		(pad "1" smd rect
			(at 0 0)
			(size 0.508 0.508)
			(layers "F.Cu" "F.Mask" "F.Paste")
			(net "A_HSC_LOW")
		)
		(pad "2" smd rect
			(at 0 0.889)
			(size 0.508 0.508)
			(layers "F.Cu" "F.Mask" "F.Paste")
			(net "AGND_HSC")
		)
		(zone
			(layer "F.Cu")
			(hatch none 0.5)
			(connect_pads
				(clearance 0)
			)
			(min_thickness 0.25)
			(keepout
				(tracks allowed)
				(vias not_allowed)
				(pads allowed)
				(copperpour not_allowed)
				(footprints allowed)
			)
			(placement
				(enabled no)
				(sheetname "")
			)
			(fill
				(thermal_gap 0.5)
				(thermal_bridge_width 0.5)
				(island_removal_mode 0)
			)
			(polygon
				(pts
					(xy 23.20798 -83.88858) (xy 23.71598 -83.88858) (xy 23.71598 -83.50758) (xy 23.20798 -83.50758)
				)
			)
		)
		(zone
			(layer "F.Cu")
			(hatch none 0.5)
			(connect_pads
				(clearance 0)
			)
			(min_thickness 0.25)
			(keepout
				(tracks not_allowed)
				(vias allowed)
				(pads allowed)
				(copperpour not_allowed)
				(footprints allowed)
			)
			(placement
				(enabled no)
				(sheetname "")
			)
			(fill
				(thermal_gap 0.5)
				(thermal_bridge_width 0.5)
				(island_removal_mode 0)
			)
			(polygon
				(pts
					(xy 23.20798 -83.50758) (xy 23.71598 -83.50758) (xy 23.71598 -83.88858) (xy 23.20798 -83.88858)
				)
			)
		)
	)
	(footprint ""
		(layer "F.Cu")
		(at 9.017 10.7315 -90)
		(property "Reference" "T1P25"
			(at 0 0 270)
			(layer "F.SilkS")
			(hide yes)
			(effects
				(font
					(size 1.27 1.27)
				)
			)
		)
		(property "Value" "*"
			(at 0 -3.44805 270)
			(unlocked yes)
			(layer "F.Fab")
			(hide yes)
			(effects
				(font
					(size 0.889 0.889)
					(thickness 0.1524)
				)
			)
		)
		(property "Device Type" "TPAD-SE-2P-GP_DISCRET-GA1-TPADA"
			(at 0 -4.97205 270)
			(unlocked yes)
			(layer "F.Fab")
			(hide yes)
			(effects
				(font
					(size 0.889 0.889)
					(thickness 0.1524)
				)
			)
		)
		(duplicate_pad_numbers_are_jumpers no)
		(fp_line
			(start -1.016 2.286)
			(end -1.016 -2.286)
			(stroke
				(width 0.1524)
				(type default)
			)
			(layer "F.SilkS")
		)
		(fp_line
			(start 1.016 2.286)
			(end -1.016 2.286)
			(stroke
				(width 0.1524)
				(type default)
			)
			(layer "F.SilkS")
		)
		(fp_line
			(start -1.016 -2.286)
			(end 1.016 -2.286)
			(stroke
				(width 0.1524)
				(type default)
			)
			(layer "F.SilkS")
		)
		(fp_line
			(start 1.016 -2.286)
			(end 1.016 2.286)
			(stroke
				(width 0.1524)
				(type default)
			)
			(layer "F.SilkS")
		)
		(fp_rect
			(start -1.27 2.54)
			(end 1.27 -2.54)
			(stroke
				(width 0)
				(type default)
			)
			(fill no)
			(layer "F.CrtYd")
		)
		(fp_rect
			(start -1.27 2.54)
			(end 1.27 -2.54)
			(stroke
				(width 0)
				(type default)
			)
			(fill no)
			(layer "F.Fab")
		)
		(pad "1" thru_hole circle
			(at 0 -1.27 270)
			(size 1.524 1.524)
			(drill 0.9144)
			(layers "*.Cu" "*.Mask")
			(remove_unused_layers no)
			(net "L1_40OHM_6INCH")
			(clearance -0.0508)
			(thermal_gap 0.127)
			(padstack
				(mode front_inner_back)
				(layer "Inner"
					(shape circle)
					(size 1.1684 1.1684)
					(clearance 0.127)
				)
				(layer "B.Cu"
					(shape circle)
					(size 1.524 1.524)
					(clearance -0.0508)
				)
			)
		)
		(pad "GND1" thru_hole rect
			(at 0 1.27 270)
			(size 1.524 1.524)
			(drill 0.9144)
			(layers "*.Cu" "*.Mask")
			(remove_unused_layers no)
			(net "GND")
			(clearance -0.0508)
			(thermal_gap 0.127)
			(padstack
				(mode front_inner_back)
				(layer "Inner"
					(shape circle)
					(size 1.1684 1.1684)
					(clearance 0.127)
				)
				(layer "B.Cu"
					(shape rect)
					(size 1.524 1.524)
					(clearance -0.0508)
				)
			)
		)
	)
	(footprint ""
		(layer "F.Cu")
		(at 33.2105 -92.9386 90)
		(property "Reference" "C1C25"
			(at 0 0 90)
			(layer "F.SilkS")
			(hide yes)
			(effects
				(font
					(size 1.27 1.27)
				)
			)
		)
		(property "Value" ""
			(at 0 0 90)
			(layer "F.Fab")
			(effects
				(font
					(size 1.27 1.27)
				)
			)
		)
		(duplicate_pad_numbers_are_jumpers no)
		(fp_rect
			(start 0.3048 0.9906)
			(end -0.3048 -0.1016)
			(stroke
				(width 0)
				(type default)
			)
			(fill no)
			(layer "F.CrtYd")
		)
		(fp_line
			(start 0.3048 -0.1016)
			(end -0.3048 -0.1016)
			(stroke
				(width 0.1)
				(type default)
			)
			(layer "F.Fab")
		)
		(fp_line
			(start -0.3048 -0.1016)
			(end -0.3048 0.9906)
			(stroke
				(width 0.1)
				(type default)
			)
			(layer "F.Fab")
		)
		(fp_line
			(start 0.3048 0.9906)
			(end 0.3048 -0.1016)
			(stroke
				(width 0.1)
				(type default)
			)
			(layer "F.Fab")
		)
		(fp_line
			(start -0.3048 0.9906)
			(end 0.3048 0.9906)
			(stroke
				(width 0.1)
				(type default)
			)
			(layer "F.Fab")
		)
		(pad "1" smd rect
			(at 0 0 90)
			(size 0.508 0.508)
			(layers "F.Cu" "F.Mask" "F.Paste")
			(net "VR_FET_SW_P12V_STBY_PVCCIN_CPU1")
		)
		(pad "2" smd rect
			(at 0 0.889 90)
			(size 0.508 0.508)
			(layers "F.Cu" "F.Mask" "F.Paste")
			(net "GND")
		)
		(zone
			(layer "F.Cu")
			(hatch none 0.5)
			(connect_pads
				(clearance 0)
			)
			(min_thickness 0.25)
			(keepout
				(tracks allowed)
				(vias not_allowed)
				(pads allowed)
				(copperpour not_allowed)
				(footprints allowed)
			)
			(placement
				(enabled no)
				(sheetname "")
			)
			(fill
				(thermal_gap 0.5)
				(thermal_bridge_width 0.5)
				(island_removal_mode 0)
			)
			(polygon
				(pts
					(xy 33.8455 -93.1926) (xy 33.4645 -93.1926) (xy 33.4645 -92.6846) (xy 33.8455 -92.6846)
				)
			)
		)
		(zone
			(layer "F.Cu")
			(hatch none 0.5)
			(connect_pads
				(clearance 0)
			)
			(min_thickness 0.25)
			(keepout
				(tracks not_allowed)
				(vias allowed)
				(pads allowed)
				(copperpour not_allowed)
				(footprints allowed)
			)
			(placement
				(enabled no)
				(sheetname "")
			)
			(fill
				(thermal_gap 0.5)
				(thermal_bridge_width 0.5)
				(island_removal_mode 0)
			)
			(polygon
				(pts
					(xy 33.8455 -93.1926) (xy 33.4645 -93.1926) (xy 33.4645 -92.6846) (xy 33.8455 -92.6846)
				)
			)
		)
	)
)
